(kicad_pcb
	(version 20240108)
	(generator "pcbnew")
	(generator_version "8.0")
	(general
		(thickness 1.6)
		(legacy_teardrops no)
	)
	(paper "A4")
	(title_block
		(title "Jetson Orin Baseboard OCuLink Expansion")
		(date "2025-03-18")
		(rev "1.1.0")
		(company "Antmicro Ltd")
		(comment 1 "www.antmicro.com")
		(comment 9 "footprints 11-12 of 119")
	)
	(layers
		(0 "F.Cu" signal)
		(1 "In1.Cu" signal)
		(2 "In2.Cu" signal)
		(31 "B.Cu" signal)
		(32 "B.Adhes" user "B.Adhesive")
		(33 "F.Adhes" user "F.Adhesive")
		(34 "B.Paste" user)
		(35 "F.Paste" user)
		(36 "B.SilkS" user "B.Silkscreen")
		(37 "F.SilkS" user "F.Silkscreen")
		(38 "B.Mask" user)
		(39 "F.Mask" user)
		(40 "Dwgs.User" user "User.Drawings")
		(41 "Cmts.User" user "User.Comments")
		(42 "Eco1.User" user "User.Eco1")
		(43 "Eco2.User" user "User.Eco2")
		(44 "Edge.Cuts" user)
		(45 "Margin" user)
		(46 "B.CrtYd" user "B.Courtyard")
		(47 "F.CrtYd" user "F.Courtyard")
		(48 "B.Fab" user)
		(49 "F.Fab" user)
	)
	(footprint "antmicro-footprints:TP_SMD_0.75mm"
		(layer "F.Cu")
		(at 114.58 125.2 180)
		(property "Reference" "TP3"
			(at -1.51 1.29 0)
			(layer "F.SilkS")
			(effects
				(font
					(size 0.7 0.7)
					(thickness 0.15)
				)
				(justify right top)
			)
		)
		(property "Value" "TP_0.75mm_SMD"
			(at 0 1.2 0)
			(layer "F.Fab")
			(effects
				(font
					(size 0.7 0.7)
					(thickness 0.15)
				)
				(justify right top)
			)
		)
		(property "Footprint" "antmicro-footprints:TP_SMD_0.75mm"
			(at 0 0 0)
			(layer "F.Fab")
			(hide yes)
			(effects
				(font
					(size 1.27 1.27)
					(thickness 0.15)
				)
			)
		)
		(property "Description" "SMT test point"
			(at 0 0 0)
			(layer "F.Fab")
			(hide yes)
			(effects
				(font
					(size 1.27 1.27)
					(thickness 0.15)
				)
			)
		)
		(property "MPN" ""
			(at 0 0 180)
			(unlocked yes)
			(layer "F.Fab")
			(hide yes)
			(effects
				(font
					(size 1 1)
					(thickness 0.15)
				)
			)
		)
		(property "Manufacturer" ""
			(at 0 0 180)
			(unlocked yes)
			(layer "F.Fab")
			(hide yes)
			(effects
				(font
					(size 1 1)
					(thickness 0.15)
				)
			)
		)
		(property "Author" "Antmicro"
			(at 0 0 180)
			(unlocked yes)
			(layer "F.Fab")
			(hide yes)
			(effects
				(font
					(size 1 1)
					(thickness 0.15)
				)
			)
		)
		(property "License" "Apache-2.0"
			(at 0 0 180)
			(unlocked yes)
			(layer "F.Fab")
			(hide yes)
			(effects
				(font
					(size 1 1)
					(thickness 0.15)
				)
			)
		)
		(property "Public" "False"
			(at 0 0 180)
			(unlocked yes)
			(layer "F.Fab")
			(hide yes)
			(effects
				(font
					(size 1 1)
					(thickness 0.15)
				)
			)
		)
		(sheetname "Root")
		(sheetfile "jetson-orin-baseboard-oculink-expansion.kicad_sch")
		(attr exclude_from_pos_files exclude_from_bom)
		(fp_circle
			(center 0 0)
			(end 0.475 0)
			(stroke
				(width 0.05)
				(type default)
			)
			(fill none)
			(layer "F.CrtYd")
		)
		(fp_text user "Author: Antmicro"
			(at -0.4 3.901 0)
			(layer "F.Fab")
			(hide yes)
			(effects
				(font
					(size 0.7 0.7)
					(thickness 0.15)
				)
				(justify right top)
			)
		)
		(fp_text user "${REFERENCE}"
			(at -0.4 2.7 0)
			(layer "F.Fab")
			(hide yes)
			(effects
				(font
					(size 0.7 0.7)
					(thickness 0.15)
				)
				(justify right top)
			)
		)
		(fp_text user "License: Apache-2.0"
			(at -0.4 5.101 0)
			(layer "F.Fab")
			(hide yes)
			(effects
				(font
					(size 0.7 0.7)
					(thickness 0.15)
				)
				(justify right top)
			)
		)
		(pad "1" smd circle
			(at 0 0 180)
			(size 0.75 0.75)
			(layers "F.Cu" "F.Mask")
			(net 107 "Net-(U3-SDA)")
			(pinfunction "1")
			(pintype "passive")
		)
	)
	(footprint "antmicro-footprints:C_0402_1005Metric"
		(layer "F.Cu")
		(at 145.554 108.6 -90)
		(descr "Capacitor SMD 0402")
		(tags "capacitor SMD 0402")
		(property "Reference" "C16"
			(at -1.1 -0.546 90)
			(layer "F.SilkS")
			(effects
				(font
					(size 0.7 0.7)
					(thickness 0.15)
				)
				(justify right top)
			)
		)
		(property "Value" "C_10u_0402"
			(at -1.022927 2.155213 90)
			(layer "F.Fab")
			(effects
				(font
					(size 0.7 0.7)
					(thickness 0.15)
				)
				(justify right top)
			)
		)
		(property "Footprint" "antmicro-footprints:C_0402_1005Metric"
			(at 0 0 90)
			(layer "F.Fab")
			(hide yes)
			(effects
				(font
					(size 1.27 1.27)
					(thickness 0.15)
				)
			)
		)
		(property "Datasheet" "https://www.yageo.com/en/Chart/Download/pdf/CC0402MRX5R5BB106"
			(at 0 0 90)
			(layer "F.Fab")
			(hide yes)
			(effects
				(font
					(size 1.27 1.27)
					(thickness 0.15)
				)
			)
		)
		(property "Description" "SMD Multilayer Ceramic Capacitor, 10 µF, 6.3 V, 0402 [1005 Metric], ± 20%, X5R, CC Series"
			(at 0 0 90)
			(layer "F.Fab")
			(hide yes)
			(effects
				(font
					(size 1.27 1.27)
					(thickness 0.15)
				)
			)
		)
		(property "MPN" "CC0402MRX5R5BB106"
			(at 0 0 -90)
			(unlocked yes)
			(layer "F.Fab")
			(hide yes)
			(effects
				(font
					(size 1 1)
					(thickness 0.15)
				)
			)
		)
		(property "Manufacturer" "YAGEO"
			(at 0 0 -90)
			(unlocked yes)
			(layer "F.Fab")
			(hide yes)
			(effects
				(font
					(size 1 1)
					(thickness 0.15)
				)
			)
		)
		(property "License" "Apache-2.0"
			(at 0 0 -90)
			(unlocked yes)
			(layer "F.Fab")
			(hide yes)
			(effects
				(font
					(size 1 1)
					(thickness 0.15)
				)
			)
		)
		(property "Author" "Antmicro"
			(at 0 0 -90)
			(unlocked yes)
			(layer "F.Fab")
			(hide yes)
			(effects
				(font
					(size 1 1)
					(thickness 0.15)
				)
			)
		)
		(property "Val" "10u"
			(at 0 0 -90)
			(unlocked yes)
			(layer "F.Fab")
			(hide yes)
			(effects
				(font
					(size 1 1)
					(thickness 0.15)
				)
			)
		)
		(property "Voltage" ""
			(at 0 0 -90)
			(unlocked yes)
			(layer "F.Fab")
			(hide yes)
			(effects
				(font
					(size 1 1)
					(thickness 0.15)
				)
			)
		)
		(property "Dielectric" ""
			(at 0 0 -90)
			(unlocked yes)
			(layer "F.Fab")
			(hide yes)
			(effects
				(font
					(size 1 1)
					(thickness 0.15)
				)
			)
		)
		(sheetname "Root")
		(sheetfile "jetson-orin-baseboard-oculink-expansion.kicad_sch")
		(attr smd)
		(fp_rect
			(start -0.925 -0.47)
			(end 0.925 0.47)
			(stroke
				(width 0.05)
				(type default)
			)
			(fill none)
			(layer "F.CrtYd")
		)
		(fp_line
			(start -0.494 0.248)
			(end -0.494 -0.25)
			(stroke
				(width 0.15)
				(type solid)
			)
			(layer "F.Fab")
		)
		(fp_line
			(start 0.504 0.248)
			(end -0.494 0.248)
			(stroke
				(width 0.15)
				(type solid)
			)
			(layer "F.Fab")
		)
		(fp_line
			(start -0.494 -0.25)
			(end 0.504 -0.25)
			(stroke
				(width 0.15)
				(type solid)
			)
			(layer "F.Fab")
		)
		(fp_line
			(start 0.504 -0.25)
			(end 0.504 0.248)
			(stroke
				(width 0.15)
				(type solid)
			)
			(layer "F.Fab")
		)
		(fp_text user "Author: Antmicro"
			(at -0.939 3.399 90)
			(layer "F.Fab")
			(hide yes)
			(effects
				(font
					(size 0.7 0.7)
					(thickness 0.15)
				)
				(justify right top)
			)
		)
		(fp_text user "${REFERENCE}"
			(at -0.939 4.599 90)
			(layer "F.Fab")
			(hide yes)
			(effects
				(font
					(size 0.7 0.7)
					(thickness 0.15)
				)
				(justify right top)
			)
		)
		(fp_text user "License: Apache-2.0"
			(at -0.939 5.799 90)
			(layer "F.Fab")
			(hide yes)
			(effects
				(font
					(size 0.7 0.7)
					(thickness 0.15)
				)
				(justify right top)
			)
		)
		(pad "1" smd roundrect
			(at -0.48 0 270)
			(size 0.59 0.64)
			(layers "F.Cu" "F.Paste" "F.Mask")
			(roundrect_rratio 0.25)
			(net 51 "GND")
			(pintype "passive")
		)
		(pad "2" smd roundrect
			(at 0.48 0 270)
			(size 0.59 0.64)
			(layers "F.Cu" "F.Paste" "F.Mask")
			(roundrect_rratio 0.25)
			(net 23 "+3V3")
			(pintype "passive")
		)
	)
)
